(kicad_pcb
	(version 20260206)
	(generator "pcbnew")
	(generator_version "10.0")
	(general
		(thickness 1.6)
		(legacy_teardrops no)
	)
	(paper "A4")
	(title_block
		(title "Bryce Canyon_F.DPB_16315-1-OCP.brd")
		(comment 1 "Bryce Canyon / footprints 80-88 of 2223")
	)
	(layers
		(0 "F.Cu" signal "TOP")
		(4 "In1.Cu" signal "L2GND")
		(6 "In2.Cu" signal "L3")
		(8 "In3.Cu" signal "L4GND")
		(10 "In4.Cu" signal "L5")
		(12 "In5.Cu" signal "L6VCC")
		(14 "In6.Cu" signal "L7VCC")
		(16 "In7.Cu" signal "L8")
		(18 "In8.Cu" signal "L9GND")
		(20 "In9.Cu" signal "L10")
		(22 "In10.Cu" signal "L11GND")
		(2 "B.Cu" signal "BOTTOM")
		(9 "F.Adhes" user "F.Adhesive")
		(11 "B.Adhes" user "B.Adhesive")
		(13 "F.Paste" user "Package Geometry/Pastemask Top")
		(15 "B.Paste" user "Package Geometry/Pastemask Bottom")
		(5 "F.SilkS" user "Ref Des/Silkscreen Top")
		(7 "B.SilkS" user "Ref Des/Silkscreen Bottom")
		(1 "F.Mask" user "Board Geometry/Soldermask Top")
		(3 "B.Mask" user "Board Geometry/Soldermask Bottom")
		(17 "Dwgs.User" user "User.Drawings")
		(19 "Cmts.User" user "User.Comments")
		(21 "Eco1.User" user "User.Eco1")
		(23 "Eco2.User" user "User.Eco2")
		(25 "Edge.Cuts" user "Board Geometry/Outline")
		(27 "Margin" user)
		(31 "F.CrtYd" user "Package Geometry/Place Bound Top")
		(29 "B.CrtYd" user "Package Geometry/Place Bound Bottom")
		(35 "F.Fab" user "Ref Des/Assembly Top")
		(33 "B.Fab" user "Ref Des/Assembly Bottom")
	)
	(footprint ""
		(layer "F.Cu")
		(at 255.415034 -5.192522 90)
		(property "Reference" "TP212"
			(at 0 0 90)
			(layer "F.SilkS")
			(hide yes)
			(effects
				(font
					(size 1.27 1.27)
				)
			)
		)
		(property "Value" "TPAD32-GP"
			(at -0.0508 -1.6764 90)
			(unlocked yes)
			(layer "F.Fab")
			(hide yes)
			(effects
				(font
					(size 1.016 1.016)
					(thickness 0.1524)
				)
			)
		)
		(property "Device Type" "TPAD32"
			(at -0.0508 -3.2004 90)
			(unlocked yes)
			(layer "F.Fab")
			(hide yes)
			(effects
				(font
					(size 1.016 1.016)
					(thickness 0.1524)
				)
			)
		)
		(duplicate_pad_numbers_are_jumpers no)
		(fp_poly
			(pts
				(arc
					(start 0 0.4064)
					(mid 0 -0.4064)
					(end 0 0.4064)
				)
			)
			(stroke
				(width 0)
				(type default)
			)
			(fill no)
			(layer "F.CrtYd")
		)
		(fp_poly
			(pts
				(arc
					(start 0 0.7112)
					(mid 0 -0.7112)
					(end 0 0.7112)
				)
			)
			(stroke
				(width 0)
				(type default)
			)
			(fill no)
			(layer "F.Fab")
		)
		(pad "1" smd circle
			(at 0 0 90)
			(size 0.8128 0.8128)
			(layers "F.Cu" "F.Mask" "F.Paste")
			(net "TP_COMP_A_NCSI_TXEN")
		)
	)
	(footprint ""
		(layer "F.Cu")
		(at 181.6862 -186.287918)
		(property "Reference" "C266"
			(at 0 0 0)
			(layer "F.SilkS")
			(hide yes)
			(effects
				(font
					(size 1.27 1.27)
				)
			)
		)
		(property "Value" "SC4D7U25V5KX-1-GP"
			(at -0.0762 -6.1214 0)
			(unlocked yes)
			(layer "F.Fab")
			(hide yes)
			(effects
				(font
					(size 1.016 1.016)
					(thickness 0.1524)
				)
			)
		)
		(property "Device Type" "C805H58"
			(at -0.0762 -8.1534 0)
			(unlocked yes)
			(layer "F.Fab")
			(hide yes)
			(effects
				(font
					(size 1.016 1.016)
					(thickness 0.1524)
				)
			)
		)
		(duplicate_pad_numbers_are_jumpers no)
		(fp_line
			(start 0.635 0)
			(end -0.635 0)
			(stroke
				(width 0.508)
				(type default)
			)
			(layer "F.SilkS")
		)
		(fp_rect
			(start -0.9652 1.778)
			(end 0.9652 -1.778)
			(stroke
				(width 0)
				(type default)
			)
			(fill no)
			(layer "F.CrtYd")
		)
		(fp_poly
			(pts
				(xy -0.9652 -1.778) (xy 0.9652 -1.778) (xy 0.9652 1.778) (xy -0.9652 1.778)
			)
			(stroke
				(width 0)
				(type default)
			)
			(fill no)
			(layer "F.Fab")
		)
		(pad "1" smd rect
			(at 0 -0.9652)
			(size 1.397 1.143)
			(layers "F.Cu" "F.Mask" "F.Paste")
			(net "P12V_HDD17")
		)
		(pad "2" smd rect
			(at 0 0.9652)
			(size 1.397 1.143)
			(layers "F.Cu" "F.Mask" "F.Paste")
			(net "GND")
		)
	)
	(footprint ""
		(layer "F.Cu")
		(at 153.232866 -136.863074 -90)
		(property "Reference" "R1081"
			(at 0 0 270)
			(layer "F.SilkS")
			(hide yes)
			(effects
				(font
					(size 1.27 1.27)
				)
			)
		)
		(property "Value" "10R2F-L-GP"
			(at 0.064008 -3.993896 270)
			(unlocked yes)
			(layer "F.Fab")
			(hide yes)
			(effects
				(font
					(size 1.016 1.016)
					(thickness 0.1524)
				)
			)
		)
		(property "Device Type" "R402H14"
			(at 0.064008 -5.517896 270)
			(unlocked yes)
			(layer "F.Fab")
			(hide yes)
			(effects
				(font
					(size 1.016 1.016)
					(thickness 0.1524)
				)
			)
		)
		(duplicate_pad_numbers_are_jumpers no)
		(fp_line
			(start -0.508 -0.9398)
			(end -0.508 0.9398)
			(stroke
				(width 0.1524)
				(type default)
			)
			(layer "F.SilkS")
		)
		(fp_line
			(start 0.508 -0.9398)
			(end -0.508 -0.9398)
			(stroke
				(width 0.1524)
				(type default)
			)
			(layer "F.SilkS")
		)
		(fp_rect
			(start -0.508 0.9398)
			(end 0.508 -0.9398)
			(stroke
				(width 0)
				(type default)
			)
			(fill no)
			(layer "F.CrtYd")
		)
		(fp_rect
			(start -0.508 0.9398)
			(end 0.508 -0.9398)
			(stroke
				(width 0)
				(type default)
			)
			(fill no)
			(layer "F.Fab")
		)
		(pad "1" smd custom
			(at 0 -0.4445 270)
			(size 0.1397 0.1397)
			(layers "F.Cu" "F.Mask" "F.Paste")
			(net "MB0_CM_SENSE_R1_N")
			(options
				(clearance outline)
				(anchor circle)
			)
			(primitives
				(gr_poly
					(pts
						(arc
							(start -0.1778 -0.2794)
							(mid -0.249642 -0.249642)
							(end -0.2794 -0.1778)
						)
						(arc
							(start -0.2794 0.1778)
							(mid -0.249642 0.249642)
							(end -0.1778 0.2794)
						)
						(arc
							(start 0.1778 0.2794)
							(mid 0.249642 0.249642)
							(end 0.2794 0.1778)
						)
						(arc
							(start 0.2794 -0.1778)
							(mid 0.249642 -0.249642)
							(end 0.1778 -0.2794)
						)
					)
					(width 0)
					(fill yes)
				)
			)
		)
		(pad "2" smd custom
			(at 0 0.4445 270)
			(size 0.1397 0.1397)
			(layers "F.Cu" "F.Mask" "F.Paste")
			(net "MB0_HS_SENSE_N")
			(options
				(clearance outline)
				(anchor circle)
			)
			(primitives
				(gr_poly
					(pts
						(arc
							(start -0.1778 -0.2794)
							(mid -0.249642 -0.249642)
							(end -0.2794 -0.1778)
						)
						(arc
							(start -0.2794 0.1778)
							(mid -0.249642 0.249642)
							(end -0.1778 0.2794)
						)
						(arc
							(start 0.1778 0.2794)
							(mid 0.249642 0.249642)
							(end 0.2794 0.1778)
						)
						(arc
							(start 0.2794 -0.1778)
							(mid 0.249642 -0.249642)
							(end 0.1778 -0.2794)
						)
					)
					(width 0)
					(fill yes)
				)
			)
		)
	)
	(footprint ""
		(layer "F.Cu")
		(at 52.559712 -140.90269 -90)
		(property "Reference" "C623"
			(at 0 0 270)
			(layer "F.SilkS")
			(hide yes)
			(effects
				(font
					(size 1.27 1.27)
				)
			)
		)
		(property "Value" "SC2200P50V2KX-2GP"
			(at 1.1811 -2.7051 270)
			(unlocked yes)
			(layer "F.Fab")
			(hide yes)
			(effects
				(font
					(size 1.016 1.016)
					(thickness 0.1524)
				)
			)
		)
		(property "Device Type" "C402H22"
			(at 1.1811 -4.2291 270)
			(unlocked yes)
			(layer "F.Fab")
			(hide yes)
			(effects
				(font
					(size 1.016 1.016)
					(thickness 0.1524)
				)
			)
		)
		(duplicate_pad_numbers_are_jumpers no)
		(fp_rect
			(start -0.4318 0.9525)
			(end 0.4318 -0.9525)
			(stroke
				(width 0)
				(type default)
			)
			(fill no)
			(layer "F.CrtYd")
		)
		(fp_rect
			(start -0.4318 0.9525)
			(end 0.4318 -0.9525)
			(stroke
				(width 0)
				(type default)
			)
			(fill no)
			(layer "F.Fab")
		)
		(pad "1" smd custom
			(at 0 -0.4445 270)
			(size 0.1524 0.1524)
			(layers "F.Cu" "F.Mask" "F.Paste")
			(net "P5V_B_LL")
			(options
				(clearance outline)
				(anchor circle)
			)
			(primitives
				(gr_poly
					(pts
						(arc
							(start 0.3048 -0.2032)
							(mid 0.275042 -0.275042)
							(end 0.2032 -0.3048)
						)
						(arc
							(start -0.2032 -0.3048)
							(mid -0.275042 -0.275042)
							(end -0.3048 -0.2032)
						)
						(arc
							(start -0.3048 0.2032)
							(mid -0.275042 0.275042)
							(end -0.2032 0.3048)
						)
						(arc
							(start 0.2032 0.3048)
							(mid 0.275042 0.275042)
							(end 0.3048 0.2032)
						)
					)
					(width 0)
					(fill yes)
				)
			)
		)
		(pad "2" smd custom
			(at 0 0.4445 270)
			(size 0.1524 0.1524)
			(layers "F.Cu" "F.Mask" "F.Paste")
			(net "P5V_B_SNB")
			(options
				(clearance outline)
				(anchor circle)
			)
			(primitives
				(gr_poly
					(pts
						(arc
							(start 0.3048 -0.2032)
							(mid 0.275042 -0.275042)
							(end 0.2032 -0.3048)
						)
						(arc
							(start -0.2032 -0.3048)
							(mid -0.275042 -0.275042)
							(end -0.3048 -0.2032)
						)
						(arc
							(start -0.3048 0.2032)
							(mid -0.275042 0.275042)
							(end -0.2032 0.3048)
						)
						(arc
							(start 0.2032 0.3048)
							(mid 0.275042 0.275042)
							(end 0.3048 0.2032)
						)
					)
					(width 0)
					(fill yes)
				)
			)
		)
	)
	(footprint ""
		(layer "F.Cu")
		(at 331.4954 -272.585942)
		(property "Reference" "R281"
			(at 0 0 0)
			(layer "F.SilkS")
			(hide yes)
			(effects
				(font
					(size 1.27 1.27)
				)
			)
		)
		(property "Value" "4K7R2J-2-GP"
			(at 0.064008 -3.993896 0)
			(unlocked yes)
			(layer "F.Fab")
			(hide yes)
			(effects
				(font
					(size 1.016 1.016)
					(thickness 0.1524)
				)
			)
		)
		(property "Device Type" "R402H16"
			(at 0.064008 -5.517896 0)
			(unlocked yes)
			(layer "F.Fab")
			(hide yes)
			(effects
				(font
					(size 1.016 1.016)
					(thickness 0.1524)
				)
			)
		)
		(duplicate_pad_numbers_are_jumpers no)
		(fp_line
			(start -0.508 -0.9398)
			(end -0.508 0.9398)
			(stroke
				(width 0.1524)
				(type default)
			)
			(layer "F.SilkS")
		)
		(fp_line
			(start 0.508 -0.9398)
			(end -0.508 -0.9398)
			(stroke
				(width 0.1524)
				(type default)
			)
			(layer "F.SilkS")
		)
		(fp_rect
			(start -0.508 0.9398)
			(end 0.508 -0.9398)
			(stroke
				(width 0)
				(type default)
			)
			(fill no)
			(layer "F.CrtYd")
		)
		(fp_rect
			(start -0.508 0.9398)
			(end 0.508 -0.9398)
			(stroke
				(width 0)
				(type default)
			)
			(fill no)
			(layer "F.Fab")
		)
		(pad "1" smd custom
			(at 0 -0.4445)
			(size 0.1397 0.1397)
			(layers "F.Cu" "F.Mask" "F.Paste")
			(net "SW_PWR_R_HDD6")
			(options
				(clearance outline)
				(anchor circle)
			)
			(primitives
				(gr_poly
					(pts
						(arc
							(start -0.1778 -0.2794)
							(mid -0.249642 -0.249642)
							(end -0.2794 -0.1778)
						)
						(arc
							(start -0.2794 0.1778)
							(mid -0.249642 0.249642)
							(end -0.1778 0.2794)
						)
						(arc
							(start 0.1778 0.2794)
							(mid 0.249642 0.249642)
							(end 0.2794 0.1778)
						)
						(arc
							(start 0.2794 -0.1778)
							(mid 0.249642 -0.249642)
							(end 0.1778 -0.2794)
						)
					)
					(width 0)
					(fill yes)
				)
			)
		)
		(pad "2" smd custom
			(at 0 0.4445)
			(size 0.1397 0.1397)
			(layers "F.Cu" "F.Mask" "F.Paste")
			(net "GND")
			(options
				(clearance outline)
				(anchor circle)
			)
			(primitives
				(gr_poly
					(pts
						(arc
							(start -0.1778 -0.2794)
							(mid -0.249642 -0.249642)
							(end -0.2794 -0.1778)
						)
						(arc
							(start -0.2794 0.1778)
							(mid -0.249642 0.249642)
							(end -0.1778 0.2794)
						)
						(arc
							(start 0.1778 0.2794)
							(mid 0.249642 0.249642)
							(end 0.2794 0.1778)
						)
						(arc
							(start 0.2794 -0.1778)
							(mid 0.249642 -0.249642)
							(end 0.1778 -0.2794)
						)
					)
					(width 0)
					(fill yes)
				)
			)
		)
	)
	(footprint ""
		(layer "F.Cu")
		(at 445.262 -192.024)
		(property "Reference" "TP112"
			(at 0 0 0)
			(layer "F.SilkS")
			(hide yes)
			(effects
				(font
					(size 1.27 1.27)
				)
			)
		)
		(property "Value" "TPAD32-GP"
			(at -0.0508 -1.6764 0)
			(unlocked yes)
			(layer "F.Fab")
			(hide yes)
			(effects
				(font
					(size 1.016 1.016)
					(thickness 0.1524)
				)
			)
		)
		(property "Device Type" "TPAD32"
			(at -0.0508 -3.2004 0)
			(unlocked yes)
			(layer "F.Fab")
			(hide yes)
			(effects
				(font
					(size 1.016 1.016)
					(thickness 0.1524)
				)
			)
		)
		(duplicate_pad_numbers_are_jumpers no)
		(fp_poly
			(pts
				(arc
					(start 0.4064 0)
					(mid -0.4064 0)
					(end 0.4064 0)
				)
			)
			(stroke
				(width 0)
				(type default)
			)
			(fill no)
			(layer "F.CrtYd")
		)
		(fp_poly
			(pts
				(arc
					(start 0.7112 0)
					(mid -0.7112 0)
					(end 0.7112 0)
				)
			)
			(stroke
				(width 0)
				(type default)
			)
			(fill no)
			(layer "F.Fab")
		)
		(pad "1" smd circle
			(at 0 0)
			(size 0.8128 0.8128)
			(layers "F.Cu" "F.Mask" "F.Paste")
			(net "ACT_HDD_22")
		)
	)
	(footprint ""
		(layer "F.Cu")
		(at 46.821852 -130.271012 -90)
		(property "Reference" "R507"
			(at 0 0 270)
			(layer "F.SilkS")
			(hide yes)
			(effects
				(font
					(size 1.27 1.27)
				)
			)
		)
		(property "Value" "4K7R2J-2-GP"
			(at 0.064008 -3.993896 270)
			(unlocked yes)
			(layer "F.Fab")
			(hide yes)
			(effects
				(font
					(size 1.016 1.016)
					(thickness 0.1524)
				)
			)
		)
		(property "Device Type" "R402H16"
			(at 0.064008 -5.517896 270)
			(unlocked yes)
			(layer "F.Fab")
			(hide yes)
			(effects
				(font
					(size 1.016 1.016)
					(thickness 0.1524)
				)
			)
		)
		(duplicate_pad_numbers_are_jumpers no)
		(fp_line
			(start -0.508 -0.9398)
			(end -0.508 0.9398)
			(stroke
				(width 0.1524)
				(type default)
			)
			(layer "F.SilkS")
		)
		(fp_line
			(start 0.508 -0.9398)
			(end -0.508 -0.9398)
			(stroke
				(width 0.1524)
				(type default)
			)
			(layer "F.SilkS")
		)
		(fp_rect
			(start -0.508 0.9398)
			(end 0.508 -0.9398)
			(stroke
				(width 0)
				(type default)
			)
			(fill no)
			(layer "F.CrtYd")
		)
		(fp_rect
			(start -0.508 0.9398)
			(end 0.508 -0.9398)
			(stroke
				(width 0)
				(type default)
			)
			(fill no)
			(layer "F.Fab")
		)
		(pad "1" smd custom
			(at 0 -0.4445 270)
			(size 0.1397 0.1397)
			(layers "F.Cu" "F.Mask" "F.Paste")
			(net "DRIVE_A_13_FLT_LED")
			(options
				(clearance outline)
				(anchor circle)
			)
			(primitives
				(gr_poly
					(pts
						(arc
							(start -0.1778 -0.2794)
							(mid -0.249642 -0.249642)
							(end -0.2794 -0.1778)
						)
						(arc
							(start -0.2794 0.1778)
							(mid -0.249642 0.249642)
							(end -0.1778 0.2794)
						)
						(arc
							(start 0.1778 0.2794)
							(mid 0.249642 0.249642)
							(end 0.2794 0.1778)
						)
						(arc
							(start 0.2794 -0.1778)
							(mid 0.249642 -0.249642)
							(end 0.1778 -0.2794)
						)
					)
					(width 0)
					(fill yes)
				)
			)
		)
		(pad "2" smd custom
			(at 0 0.4445 270)
			(size 0.1397 0.1397)
			(layers "F.Cu" "F.Mask" "F.Paste")
			(net "GND")
			(options
				(clearance outline)
				(anchor circle)
			)
			(primitives
				(gr_poly
					(pts
						(arc
							(start -0.1778 -0.2794)
							(mid -0.249642 -0.249642)
							(end -0.2794 -0.1778)
						)
						(arc
							(start -0.2794 0.1778)
							(mid -0.249642 0.249642)
							(end -0.1778 0.2794)
						)
						(arc
							(start 0.1778 0.2794)
							(mid 0.249642 0.249642)
							(end 0.2794 0.1778)
						)
						(arc
							(start 0.2794 -0.1778)
							(mid 0.249642 -0.249642)
							(end 0.1778 -0.2794)
						)
					)
					(width 0)
					(fill yes)
				)
			)
		)
	)
	(footprint ""
		(layer "F.Cu")
		(at 265.887962 -222.104458)
		(property "Reference" "R401"
			(at 0 0 0)
			(layer "F.SilkS")
			(hide yes)
			(effects
				(font
					(size 1.27 1.27)
				)
			)
		)
		(property "Value" "10KR2F-2-GP"
			(at 0.064008 -3.993896 0)
			(unlocked yes)
			(layer "F.Fab")
			(hide yes)
			(effects
				(font
					(size 1.016 1.016)
					(thickness 0.1524)
				)
			)
		)
		(property "Device Type" "R402H16"
			(at 0.064008 -5.517896 0)
			(unlocked yes)
			(layer "F.Fab")
			(hide yes)
			(effects
				(font
					(size 1.016 1.016)
					(thickness 0.1524)
				)
			)
		)
		(duplicate_pad_numbers_are_jumpers no)
		(fp_line
			(start -0.508 -0.9398)
			(end -0.508 0.9398)
			(stroke
				(width 0.1524)
				(type default)
			)
			(layer "F.SilkS")
		)
		(fp_line
			(start 0.508 -0.9398)
			(end -0.508 -0.9398)
			(stroke
				(width 0.1524)
				(type default)
			)
			(layer "F.SilkS")
		)
		(fp_rect
			(start -0.508 0.9398)
			(end 0.508 -0.9398)
			(stroke
				(width 0)
				(type default)
			)
			(fill no)
			(layer "F.CrtYd")
		)
		(fp_rect
			(start -0.508 0.9398)
			(end 0.508 -0.9398)
			(stroke
				(width 0)
				(type default)
			)
			(fill no)
			(layer "F.Fab")
		)
		(pad "1" smd custom
			(at 0 -0.4445)
			(size 0.1397 0.1397)
			(layers "F.Cu" "F.Mask" "F.Paste")
			(net "P3V3_STBY_A")
			(options
				(clearance outline)
				(anchor circle)
			)
			(primitives
				(gr_poly
					(pts
						(arc
							(start -0.1778 -0.2794)
							(mid -0.249642 -0.249642)
							(end -0.2794 -0.1778)
						)
						(arc
							(start -0.2794 0.1778)
							(mid -0.249642 0.249642)
							(end -0.1778 0.2794)
						)
						(arc
							(start 0.1778 0.2794)
							(mid 0.249642 0.249642)
							(end 0.2794 0.1778)
						)
						(arc
							(start 0.2794 -0.1778)
							(mid 0.249642 -0.249642)
							(end 0.1778 -0.2794)
						)
					)
					(width 0)
					(fill yes)
				)
			)
		)
		(pad "2" smd custom
			(at 0 0.4445)
			(size 0.1397 0.1397)
			(layers "F.Cu" "F.Mask" "F.Paste")
			(net "I2C_DPB_BUFF_READY")
			(options
				(clearance outline)
				(anchor circle)
			)
			(primitives
				(gr_poly
					(pts
						(arc
							(start -0.1778 -0.2794)
							(mid -0.249642 -0.249642)
							(end -0.2794 -0.1778)
						)
						(arc
							(start -0.2794 0.1778)
							(mid -0.249642 0.249642)
							(end -0.1778 0.2794)
						)
						(arc
							(start 0.1778 0.2794)
							(mid 0.249642 0.249642)
							(end 0.2794 0.1778)
						)
						(arc
							(start 0.2794 -0.1778)
							(mid 0.249642 -0.249642)
							(end 0.1778 -0.2794)
						)
					)
					(width 0)
					(fill yes)
				)
			)
		)
	)
	(footprint ""
		(layer "F.Cu")
		(at 456.0189 -304.335942 180)
		(property "Reference" "C177"
			(at 0 0 180)
			(layer "F.SilkS")
			(hide yes)
			(effects
				(font
					(size 1.27 1.27)
				)
			)
		)
		(property "Value" "SC1U25V3KX-GP"
			(at 0 -2.8194 180)
			(unlocked yes)
			(layer "F.Fab")
			(hide yes)
			(effects
				(font
					(size 1.016 1.016)
					(thickness 0.1524)
				)
			)
		)
		(property "Device Type" "C603H36"
			(at 0 -4.3434 180)
			(unlocked yes)
			(layer "F.Fab")
			(hide yes)
			(effects
				(font
					(size 1.016 1.016)
					(thickness 0.1524)
				)
			)
		)
		(duplicate_pad_numbers_are_jumpers no)
		(fp_line
			(start 0.508 0)
			(end -0.508 0)
			(stroke
				(width 0.2032)
				(type default)
			)
			(layer "F.SilkS")
		)
		(fp_rect
			(start -0.5842 1.3335)
			(end 0.5842 -1.3335)
			(stroke
				(width 0)
				(type default)
			)
			(fill no)
			(layer "F.CrtYd")
		)
		(fp_rect
			(start -0.5842 1.3335)
			(end 0.5842 -1.3335)
			(stroke
				(width 0)
				(type default)
			)
			(fill no)
			(layer "F.Fab")
		)
		(pad "1" smd custom
			(at 0 -0.762 180)
			(size 0.2159 0.2159)
			(layers "F.Cu" "F.Mask" "F.Paste")
			(net "P12V_HDD10")
			(options
				(clearance outline)
				(anchor circle)
			)
			(primitives
				(gr_poly
					(pts
						(arc
							(start -0.3302 -0.4318)
							(mid -0.402042 -0.402042)
							(end -0.4318 -0.3302)
						)
						(arc
							(start -0.4318 0.3302)
							(mid -0.402042 0.402042)
							(end -0.3302 0.4318)
						)
						(arc
							(start 0.3302 0.4318)
							(mid 0.402042 0.402042)
							(end 0.4318 0.3302)
						)
						(arc
							(start 0.4318 -0.3302)
							(mid 0.402042 -0.402042)
							(end 0.3302 -0.4318)
						)
					)
					(width 0)
					(fill yes)
				)
			)
		)
		(pad "2" smd custom
			(at 0 0.762 180)
			(size 0.2159 0.2159)
			(layers "F.Cu" "F.Mask" "F.Paste")
			(net "GND")
			(options
				(clearance outline)
				(anchor circle)
			)
			(primitives
				(gr_poly
					(pts
						(arc
							(start -0.3302 -0.4318)
							(mid -0.402042 -0.402042)
							(end -0.4318 -0.3302)
						)
						(arc
							(start -0.4318 0.3302)
							(mid -0.402042 0.402042)
							(end -0.3302 0.4318)
						)
						(arc
							(start 0.3302 0.4318)
							(mid 0.402042 0.402042)
							(end 0.4318 0.3302)
						)
						(arc
							(start 0.4318 -0.3302)
							(mid 0.402042 -0.402042)
							(end 0.3302 -0.4318)
						)
					)
					(width 0)
					(fill yes)
				)
			)
		)
	)
)
